(kicad_pcb
	(version 20260206)
	(generator "pcbnew")
	(generator_version "10.0")
	(general
		(thickness 1.6)
		(legacy_teardrops no)
	)
	(paper "A4")
	(title_block
		(title "04192023_DAF0TMB3IC0_F0TG_MB_C_brd_V02_OCP.brd")
		(comment 1 "Grand Teton / footprints 3205-3213 of 8354")
	)
	(layers
		(0 "F.Cu" signal "TOP")
		(4 "In1.Cu" signal "GND")
		(6 "In2.Cu" signal "IN1")
		(8 "In3.Cu" signal "GND1")
		(10 "In4.Cu" signal "IN2")
		(12 "In5.Cu" signal "GND2")
		(14 "In6.Cu" signal "IN3")
		(16 "In7.Cu" signal "GND3")
		(18 "In8.Cu" signal "VCC")
		(20 "In9.Cu" signal "VCC1")
		(22 "In10.Cu" signal "GND4")
		(24 "In11.Cu" signal "IN4")
		(26 "In12.Cu" signal "GND5")
		(28 "In13.Cu" signal "IN5")
		(30 "In14.Cu" signal "GND6")
		(32 "In15.Cu" signal "IN6")
		(34 "In16.Cu" signal "GND7")
		(2 "B.Cu" signal "BOTTOM")
		(9 "F.Adhes" user "F.Adhesive")
		(11 "B.Adhes" user "B.Adhesive")
		(13 "F.Paste" user "Package Geometry/Pastemask Top")
		(15 "B.Paste" user "Package Geometry/Pastemask Bottom")
		(5 "F.SilkS" user "Ref Des/Silkscreen Top")
		(7 "B.SilkS" user "Ref Des/Silkscreen Bottom")
		(1 "F.Mask" user "Board Geometry/Soldermask Top")
		(3 "B.Mask" user "Board Geometry/Soldermask Bottom")
		(17 "Dwgs.User" user "User.Drawings")
		(19 "Cmts.User" user "User.Comments")
		(21 "Eco1.User" user "User.Eco1")
		(23 "Eco2.User" user "User.Eco2")
		(25 "Edge.Cuts" user "Board Geometry/Outline")
		(27 "Margin" user)
		(31 "F.CrtYd" user "Package Geometry/Place Bound Top")
		(29 "B.CrtYd" user "Package Geometry/Place Bound Bottom")
		(35 "F.Fab" user "Ref Des/Assembly Top")
		(33 "B.Fab" user "Ref Des/Assembly Bottom")
	)
	(footprint ""
		(layer "F.Cu")
		(at 252.573536 -120.31345 180)
		(property "Reference" "R1497"
			(at 0 0 180)
			(layer "F.SilkS")
			(hide yes)
			(effects
				(font
					(size 1.27 1.27)
				)
			)
		)
		(property "Value" ""
			(at 0 0 180)
			(layer "F.Fab")
			(effects
				(font
					(size 1.27 1.27)
				)
			)
		)
		(duplicate_pad_numbers_are_jumpers no)
		(fp_line
			(start 0.7874 0.4064)
			(end -0.7874 0.4064)
			(stroke
				(width 0.1524)
				(type default)
			)
			(layer "F.SilkS")
		)
		(fp_line
			(start 0.7874 -0.4064)
			(end 0.7874 0.4064)
			(stroke
				(width 0.1524)
				(type default)
			)
			(layer "F.SilkS")
		)
		(fp_line
			(start -0.7874 0.4064)
			(end -0.7874 -0.4064)
			(stroke
				(width 0.1524)
				(type default)
			)
			(layer "F.SilkS")
		)
		(fp_line
			(start -0.7874 -0.4064)
			(end 0.7874 -0.4064)
			(stroke
				(width 0.1524)
				(type default)
			)
			(layer "F.SilkS")
		)
		(fp_line
			(start 0.67945 0.3048)
			(end 0.120396 0.3048)
			(stroke
				(width 0.1)
				(type default)
			)
			(layer "F.Fab")
		)
		(fp_line
			(start 0.67945 -0.3048)
			(end 0.67945 0.3048)
			(stroke
				(width 0.1)
				(type default)
			)
			(layer "F.Fab")
		)
		(fp_line
			(start 0.12065 -0.2794)
			(end 0.12065 -0.3048)
			(stroke
				(width 0.1)
				(type default)
			)
			(layer "F.Fab")
		)
		(fp_line
			(start 0.12065 -0.3048)
			(end 0.67945 -0.3048)
			(stroke
				(width 0.1)
				(type default)
			)
			(layer "F.Fab")
		)
		(fp_line
			(start 0.120396 0.3048)
			(end 0.120396 0.2794)
			(stroke
				(width 0.1)
				(type default)
			)
			(layer "F.Fab")
		)
		(fp_line
			(start 0.120396 0.2794)
			(end -0.12065 0.2794)
			(stroke
				(width 0.1)
				(type default)
			)
			(layer "F.Fab")
		)
		(fp_line
			(start -0.12065 0.3048)
			(end -0.67945 0.3048)
			(stroke
				(width 0.1)
				(type default)
			)
			(layer "F.Fab")
		)
		(fp_line
			(start -0.12065 0.2794)
			(end -0.12065 0.3048)
			(stroke
				(width 0.1)
				(type default)
			)
			(layer "F.Fab")
		)
		(fp_line
			(start -0.12065 -0.2794)
			(end 0.12065 -0.2794)
			(stroke
				(width 0.1)
				(type default)
			)
			(layer "F.Fab")
		)
		(fp_line
			(start -0.12065 -0.305054)
			(end -0.12065 -0.2794)
			(stroke
				(width 0.1)
				(type default)
			)
			(layer "F.Fab")
		)
		(fp_line
			(start -0.67945 0.3048)
			(end -0.67945 -0.305054)
			(stroke
				(width 0.1)
				(type default)
			)
			(layer "F.Fab")
		)
		(fp_line
			(start -0.67945 -0.305054)
			(end -0.12065 -0.305054)
			(stroke
				(width 0.1)
				(type default)
			)
			(layer "F.Fab")
		)
		(pad "1" smd circle
			(at -0.40005 0 180)
			(size 0 0)
			(layers "F.Cu" "F.Mask" "F.Paste")
			(net "SMB_VR_3V3AUX_SCL")
		)
		(pad "2" smd circle
			(at 0.40005 0 180)
			(size 0 0)
			(layers "F.Cu" "F.Mask" "F.Paste")
			(net "SMB_SCM_2_R3_SCL")
		)
	)
	(footprint ""
		(layer "F.Cu")
		(at 24.765 -359.918)
		(property "Reference" "PR8011"
			(at 0 0 0)
			(layer "F.SilkS")
			(hide yes)
			(effects
				(font
					(size 1.27 1.27)
				)
			)
		)
		(property "Value" ""
			(at 0 0 0)
			(layer "F.Fab")
			(effects
				(font
					(size 1.27 1.27)
				)
			)
		)
		(duplicate_pad_numbers_are_jumpers no)
		(fp_line
			(start -0.7874 -0.4064)
			(end 0.7874 -0.4064)
			(stroke
				(width 0.1524)
				(type default)
			)
			(layer "F.SilkS")
		)
		(fp_line
			(start -0.7874 0.4064)
			(end -0.7874 -0.4064)
			(stroke
				(width 0.1524)
				(type default)
			)
			(layer "F.SilkS")
		)
		(fp_line
			(start 0.7874 -0.4064)
			(end 0.7874 0.4064)
			(stroke
				(width 0.1524)
				(type default)
			)
			(layer "F.SilkS")
		)
		(fp_line
			(start 0.7874 0.4064)
			(end -0.7874 0.4064)
			(stroke
				(width 0.1524)
				(type default)
			)
			(layer "F.SilkS")
		)
		(fp_line
			(start -0.67945 -0.305054)
			(end -0.12065 -0.305054)
			(stroke
				(width 0.1)
				(type default)
			)
			(layer "F.Fab")
		)
		(fp_line
			(start -0.67945 0.3048)
			(end -0.67945 -0.305054)
			(stroke
				(width 0.1)
				(type default)
			)
			(layer "F.Fab")
		)
		(fp_line
			(start -0.12065 -0.305054)
			(end -0.12065 -0.2794)
			(stroke
				(width 0.1)
				(type default)
			)
			(layer "F.Fab")
		)
		(fp_line
			(start -0.12065 -0.2794)
			(end 0.12065 -0.2794)
			(stroke
				(width 0.1)
				(type default)
			)
			(layer "F.Fab")
		)
		(fp_line
			(start -0.12065 0.2794)
			(end -0.12065 0.3048)
			(stroke
				(width 0.1)
				(type default)
			)
			(layer "F.Fab")
		)
		(fp_line
			(start -0.12065 0.3048)
			(end -0.67945 0.3048)
			(stroke
				(width 0.1)
				(type default)
			)
			(layer "F.Fab")
		)
		(fp_line
			(start 0.120396 0.2794)
			(end -0.12065 0.2794)
			(stroke
				(width 0.1)
				(type default)
			)
			(layer "F.Fab")
		)
		(fp_line
			(start 0.120396 0.3048)
			(end 0.120396 0.2794)
			(stroke
				(width 0.1)
				(type default)
			)
			(layer "F.Fab")
		)
		(fp_line
			(start 0.12065 -0.3048)
			(end 0.67945 -0.3048)
			(stroke
				(width 0.1)
				(type default)
			)
			(layer "F.Fab")
		)
		(fp_line
			(start 0.12065 -0.2794)
			(end 0.12065 -0.3048)
			(stroke
				(width 0.1)
				(type default)
			)
			(layer "F.Fab")
		)
		(fp_line
			(start 0.67945 -0.3048)
			(end 0.67945 0.3048)
			(stroke
				(width 0.1)
				(type default)
			)
			(layer "F.Fab")
		)
		(fp_line
			(start 0.67945 0.3048)
			(end 0.120396 0.3048)
			(stroke
				(width 0.1)
				(type default)
			)
			(layer "F.Fab")
		)
		(pad "1" smd circle
			(at -0.40005 0)
			(size 0 0)
			(layers "F.Cu" "F.Mask" "F.Paste")
			(net "SVID_PVDDCR_CPU1_P1_SVC_R")
		)
		(pad "2" smd circle
			(at 0.40005 0)
			(size 0 0)
			(layers "F.Cu" "F.Mask" "F.Paste")
			(net "SVID_PVDDCR_CPU1_P1_SVC_R1")
		)
	)
	(footprint ""
		(layer "F.Cu")
		(at 278.254206 -433.706016 -90)
		(property "Reference" "U308"
			(at 0.740664 -2.003552 0)
			(unlocked yes)
			(layer "F.SilkS")
			(effects
				(font
					(size 0.7874 0.5842)
					(thickness 0.1524)
				)
				(justify left)
			)
		)
		(property "Value" ""
			(at 0 0 270)
			(layer "F.Fab")
			(effects
				(font
					(size 1.27 1.27)
				)
			)
		)
		(duplicate_pad_numbers_are_jumpers no)
		(fp_line
			(start -1.38176 1.100074)
			(end 1.38176 1.100074)
			(stroke
				(width 0.1524)
				(type default)
			)
			(layer "F.SilkS")
		)
		(fp_line
			(start 1.38176 1.100074)
			(end 1.38176 -1.100074)
			(stroke
				(width 0.1524)
				(type default)
			)
			(layer "F.SilkS")
		)
		(fp_line
			(start 0 -0.508)
			(end -0.592074 -1.100074)
			(stroke
				(width 0.1524)
				(type default)
			)
			(layer "F.SilkS")
		)
		(fp_line
			(start -1.38176 -1.100074)
			(end -1.38176 1.100074)
			(stroke
				(width 0.1524)
				(type default)
			)
			(layer "F.SilkS")
		)
		(fp_line
			(start -0.592074 -1.100074)
			(end -1.38176 -1.100074)
			(stroke
				(width 0.1524)
				(type default)
			)
			(layer "F.SilkS")
		)
		(fp_line
			(start 0.592074 -1.100074)
			(end 0 -0.508)
			(stroke
				(width 0.1524)
				(type default)
			)
			(layer "F.SilkS")
		)
		(fp_line
			(start 1.38176 -1.100074)
			(end 0.592074 -1.100074)
			(stroke
				(width 0.1524)
				(type default)
			)
			(layer "F.SilkS")
		)
		(fp_poly
			(pts
				(xy -1.528318 -1.73355) (xy -1.372362 -1.26619) (xy -1.839722 -1.422146)
			)
			(stroke
				(width 0)
				(type default)
			)
			(fill yes)
			(layer "F.SilkS")
		)
		(fp_line
			(start -0.674878 1.100074)
			(end 0.674878 1.100074)
			(stroke
				(width 0.1)
				(type default)
			)
			(layer "F.Fab")
		)
		(fp_line
			(start 0.674878 1.100074)
			(end 0.674878 -1.100074)
			(stroke
				(width 0.1)
				(type default)
			)
			(layer "F.Fab")
		)
		(fp_line
			(start -0.674878 -1.100074)
			(end -0.674878 1.100074)
			(stroke
				(width 0.1)
				(type default)
			)
			(layer "F.Fab")
		)
		(fp_line
			(start 0.674878 -1.100074)
			(end -0.674878 -1.100074)
			(stroke
				(width 0.1)
				(type default)
			)
			(layer "F.Fab")
		)
		(fp_poly
			(pts
				(xy -1.9431 -0.870204) (xy -1.50241 -0.649986) (xy -1.9431 -0.429768)
			)
			(stroke
				(width 0)
				(type default)
			)
			(fill yes)
			(layer "F.Fab")
		)
		(pad "1" smd rect
			(at -0.94996 -0.649986 180)
			(size 0.4318 0.6096)
			(layers "F.Cu" "F.Mask" "F.Paste")
			(net "PWRGD_P3V3_AUX_PDB_R")
		)
		(pad "2" smd rect
			(at -0.94996 0 180)
			(size 0.4318 0.6096)
			(layers "F.Cu" "F.Mask" "F.Paste")
			(net "GND")
		)
		(pad "3" smd rect
			(at -0.94996 0.649986 180)
			(size 0.4318 0.6096)
			(layers "F.Cu" "F.Mask" "F.Paste")
			(net "Net_10754")
		)
		(pad "4" smd rect
			(at 0.94996 0.649986 180)
			(size 0.4318 0.6096)
			(layers "F.Cu" "F.Mask" "F.Paste")
			(net "Net_10753")
		)
		(pad "5" smd rect
			(at 0.94996 0 180)
			(size 0.4318 0.6096)
			(layers "F.Cu" "F.Mask" "F.Paste")
			(net "P3V3_AUX")
		)
		(pad "6" smd rect
			(at 0.94996 -0.649986 180)
			(size 0.4318 0.6096)
			(layers "F.Cu" "F.Mask" "F.Paste")
			(net "PWRGD_P3V3_AUX_PDB_BUF_R")
		)
	)
	(footprint ""
		(layer "F.Cu")
		(at 358.796082 -258.795012)
		(property "Reference" "C2614"
			(at 0 0 0)
			(layer "F.SilkS")
			(hide yes)
			(effects
				(font
					(size 1.27 1.27)
				)
			)
		)
		(property "Value" ""
			(at 0 0 0)
			(layer "F.Fab")
			(effects
				(font
					(size 1.27 1.27)
				)
			)
		)
		(duplicate_pad_numbers_are_jumpers no)
		(fp_line
			(start -0.7874 -0.4064)
			(end 0.7874 -0.4064)
			(stroke
				(width 0.1524)
				(type default)
			)
			(layer "F.SilkS")
		)
		(fp_line
			(start -0.7874 0.4064)
			(end -0.7874 -0.4064)
			(stroke
				(width 0.1524)
				(type default)
			)
			(layer "F.SilkS")
		)
		(fp_line
			(start 0.7874 -0.4064)
			(end 0.7874 0.4064)
			(stroke
				(width 0.1524)
				(type default)
			)
			(layer "F.SilkS")
		)
		(fp_line
			(start 0.7874 0.4064)
			(end -0.7874 0.4064)
			(stroke
				(width 0.1524)
				(type default)
			)
			(layer "F.SilkS")
		)
		(fp_line
			(start -0.67945 -0.305054)
			(end -0.12065 -0.305054)
			(stroke
				(width 0.1)
				(type default)
			)
			(layer "F.Fab")
		)
		(fp_line
			(start -0.67945 0.3048)
			(end -0.67945 -0.305054)
			(stroke
				(width 0.1)
				(type default)
			)
			(layer "F.Fab")
		)
		(fp_line
			(start -0.12065 -0.305054)
			(end -0.12065 -0.2794)
			(stroke
				(width 0.1)
				(type default)
			)
			(layer "F.Fab")
		)
		(fp_line
			(start -0.12065 -0.2794)
			(end 0.12065 -0.2794)
			(stroke
				(width 0.1)
				(type default)
			)
			(layer "F.Fab")
		)
		(fp_line
			(start -0.12065 0.2794)
			(end -0.12065 0.3048)
			(stroke
				(width 0.1)
				(type default)
			)
			(layer "F.Fab")
		)
		(fp_line
			(start -0.12065 0.3048)
			(end -0.67945 0.3048)
			(stroke
				(width 0.1)
				(type default)
			)
			(layer "F.Fab")
		)
		(fp_line
			(start 0.120396 0.2794)
			(end -0.12065 0.2794)
			(stroke
				(width 0.1)
				(type default)
			)
			(layer "F.Fab")
		)
		(fp_line
			(start 0.120396 0.3048)
			(end 0.120396 0.2794)
			(stroke
				(width 0.1)
				(type default)
			)
			(layer "F.Fab")
		)
		(fp_line
			(start 0.12065 -0.3048)
			(end 0.67945 -0.3048)
			(stroke
				(width 0.1)
				(type default)
			)
			(layer "F.Fab")
		)
		(fp_line
			(start 0.12065 -0.2794)
			(end 0.12065 -0.3048)
			(stroke
				(width 0.1)
				(type default)
			)
			(layer "F.Fab")
		)
		(fp_line
			(start 0.67945 -0.3048)
			(end 0.67945 0.3048)
			(stroke
				(width 0.1)
				(type default)
			)
			(layer "F.Fab")
		)
		(fp_line
			(start 0.67945 0.3048)
			(end 0.120396 0.3048)
			(stroke
				(width 0.1)
				(type default)
			)
			(layer "F.Fab")
		)
		(pad "1" smd circle
			(at -0.40005 0)
			(size 0 0)
			(layers "F.Cu" "F.Mask" "F.Paste")
			(net "PVDD11_S3_P0")
		)
		(pad "2" smd circle
			(at 0.40005 0)
			(size 0 0)
			(layers "F.Cu" "F.Mask" "F.Paste")
			(net "GND")
		)
	)
	(footprint ""
		(layer "F.Cu")
		(at 298.967144 -389.86206 180)
		(property "Reference" "C932"
			(at 0 0 180)
			(layer "F.SilkS")
			(hide yes)
			(effects
				(font
					(size 1.27 1.27)
				)
			)
		)
		(property "Value" ""
			(at 0 0 180)
			(layer "F.Fab")
			(effects
				(font
					(size 1.27 1.27)
				)
			)
		)
		(duplicate_pad_numbers_are_jumpers no)
		(fp_line
			(start 0.299974 0.150114)
			(end -0.299974 0.150114)
			(stroke
				(width 0.1)
				(type default)
			)
			(layer "F.Fab")
		)
		(fp_line
			(start 0.299974 -0.150114)
			(end 0.299974 0.150114)
			(stroke
				(width 0.1)
				(type default)
			)
			(layer "F.Fab")
		)
		(fp_line
			(start -0.299974 0.150114)
			(end -0.299974 -0.150114)
			(stroke
				(width 0.1)
				(type default)
			)
			(layer "F.Fab")
		)
		(fp_line
			(start -0.299974 -0.150114)
			(end 0.299974 -0.150114)
			(stroke
				(width 0.1)
				(type default)
			)
			(layer "F.Fab")
		)
		(pad "1" smd rect
			(at -0.2667 0 180)
			(size 0.3048 0.381)
			(layers "F.Cu" "F.Mask" "F.Paste")
			(net "P5E_CPU0_P0_TX_C_DN<0>")
		)
		(pad "2" smd rect
			(at 0.2667 0 180)
			(size 0.3048 0.381)
			(layers "F.Cu" "F.Mask" "F.Paste")
			(net "P5E_CPU0_P0_TX_DN<0>")
		)
	)
	(footprint ""
		(layer "F.Cu")
		(at 74.5236 -385.48056)
		(property "Reference" "R781"
			(at 0 0 0)
			(layer "F.SilkS")
			(hide yes)
			(effects
				(font
					(size 1.27 1.27)
				)
			)
		)
		(property "Value" ""
			(at 0 0 0)
			(layer "F.Fab")
			(effects
				(font
					(size 1.27 1.27)
				)
			)
		)
		(duplicate_pad_numbers_are_jumpers no)
		(fp_line
			(start -0.32512 -0.175006)
			(end 0.32512 -0.175006)
			(stroke
				(width 0.1)
				(type default)
			)
			(layer "F.Fab")
		)
		(fp_line
			(start -0.32512 0.175006)
			(end -0.32512 -0.175006)
			(stroke
				(width 0.1)
				(type default)
			)
			(layer "F.Fab")
		)
		(fp_line
			(start 0.32512 -0.175006)
			(end 0.32512 0.175006)
			(stroke
				(width 0.1)
				(type default)
			)
			(layer "F.Fab")
		)
		(fp_line
			(start 0.32512 0.175006)
			(end -0.32512 0.175006)
			(stroke
				(width 0.1)
				(type default)
			)
			(layer "F.Fab")
		)
		(pad "1" smd rect
			(at -0.2667 0)
			(size 0.3048 0.381)
			(layers "F.Cu" "F.Mask" "F.Paste")
			(net "P1V8_CPU1_RT_1D")
		)
		(pad "2" smd rect
			(at 0.2667 0 180)
			(size 0.3048 0.381)
			(layers "F.Cu" "F.Mask" "F.Paste")
			(net "GPIO2_RT_CPU1_P1")
		)
	)
	(footprint ""
		(layer "F.Cu")
		(at 37.860478 -16.099536 90)
		(property "Reference" "C694"
			(at 0 0 90)
			(layer "F.SilkS")
			(hide yes)
			(effects
				(font
					(size 1.27 1.27)
				)
			)
		)
		(property "Value" ""
			(at 0 0 90)
			(layer "F.Fab")
			(effects
				(font
					(size 1.27 1.27)
				)
			)
		)
		(duplicate_pad_numbers_are_jumpers no)
		(fp_line
			(start 0.299974 -0.150114)
			(end 0.299974 0.150114)
			(stroke
				(width 0.1)
				(type default)
			)
			(layer "F.Fab")
		)
		(fp_line
			(start -0.299974 -0.150114)
			(end 0.299974 -0.150114)
			(stroke
				(width 0.1)
				(type default)
			)
			(layer "F.Fab")
		)
		(fp_line
			(start 0.299974 0.150114)
			(end -0.299974 0.150114)
			(stroke
				(width 0.1)
				(type default)
			)
			(layer "F.Fab")
		)
		(fp_line
			(start -0.299974 0.150114)
			(end -0.299974 -0.150114)
			(stroke
				(width 0.1)
				(type default)
			)
			(layer "F.Fab")
		)
		(pad "1" smd rect
			(at -0.2667 0 90)
			(size 0.3048 0.381)
			(layers "F.Cu" "F.Mask" "F.Paste")
			(net "P5E_CPU1_G1_TX_C_DN<7>")
		)
		(pad "2" smd rect
			(at 0.2667 0 90)
			(size 0.3048 0.381)
			(layers "F.Cu" "F.Mask" "F.Paste")
			(net "P5E_CPU1_G1_TX_DN<7>")
		)
	)
	(footprint ""
		(layer "F.Cu")
		(at 162.5092 -419.0492 90)
		(property "Reference" "R694"
			(at 0 0 90)
			(layer "F.SilkS")
			(hide yes)
			(effects
				(font
					(size 1.27 1.27)
				)
			)
		)
		(property "Value" ""
			(at 0 0 90)
			(layer "F.Fab")
			(effects
				(font
					(size 1.27 1.27)
				)
			)
		)
		(duplicate_pad_numbers_are_jumpers no)
		(fp_line
			(start 0.32512 -0.175006)
			(end 0.32512 0.175006)
			(stroke
				(width 0.1)
				(type default)
			)
			(layer "F.Fab")
		)
		(fp_line
			(start -0.32512 -0.175006)
			(end 0.32512 -0.175006)
			(stroke
				(width 0.1)
				(type default)
			)
			(layer "F.Fab")
		)
		(fp_line
			(start 0.32512 0.175006)
			(end -0.32512 0.175006)
			(stroke
				(width 0.1)
				(type default)
			)
			(layer "F.Fab")
		)
		(fp_line
			(start -0.32512 0.175006)
			(end -0.32512 -0.175006)
			(stroke
				(width 0.1)
				(type default)
			)
			(layer "F.Fab")
		)
		(pad "1" smd rect
			(at -0.2667 0 90)
			(size 0.3048 0.381)
			(layers "F.Cu" "F.Mask" "F.Paste")
			(net "SMB_RT_CPU1_P2_ROM_R_SDA")
		)
		(pad "2" smd rect
			(at 0.2667 0 270)
			(size 0.3048 0.381)
			(layers "F.Cu" "F.Mask" "F.Paste")
			(net "SMB_RT_CPU1_P2_ROM_SDA")
		)
	)
	(footprint ""
		(layer "F.Cu")
		(at 240.854484 -56.527192)
		(property "Reference" "C1992"
			(at 0 0 0)
			(layer "F.SilkS")
			(hide yes)
			(effects
				(font
					(size 1.27 1.27)
				)
			)
		)
		(property "Value" ""
			(at 0 0 0)
			(layer "F.Fab")
			(effects
				(font
					(size 1.27 1.27)
				)
			)
		)
		(duplicate_pad_numbers_are_jumpers no)
		(fp_line
			(start -0.299974 -0.150114)
			(end 0.299974 -0.150114)
			(stroke
				(width 0.1)
				(type default)
			)
			(layer "F.Fab")
		)
		(fp_line
			(start -0.299974 0.150114)
			(end -0.299974 -0.150114)
			(stroke
				(width 0.1)
				(type default)
			)
			(layer "F.Fab")
		)
		(fp_line
			(start 0.299974 -0.150114)
			(end 0.299974 0.150114)
			(stroke
				(width 0.1)
				(type default)
			)
			(layer "F.Fab")
		)
		(fp_line
			(start 0.299974 0.150114)
			(end -0.299974 0.150114)
			(stroke
				(width 0.1)
				(type default)
			)
			(layer "F.Fab")
		)
		(pad "1" smd rect
			(at -0.2667 0)
			(size 0.3048 0.381)
			(layers "F.Cu" "F.Mask" "F.Paste")
			(net "P3E_CPU0_P4_TX_C_DN<2>")
		)
		(pad "2" smd rect
			(at 0.2667 0)
			(size 0.3048 0.381)
			(layers "F.Cu" "F.Mask" "F.Paste")
			(net "P3E_CPU0_P4_TX_DN<2>")
		)
	)
)
